(kicad_pcb
	(version 20260206)
	(generator "pcbnew")
	(generator_version "10.0")
	(general
		(thickness 1.6)
		(legacy_teardrops no)
	)
	(paper "A4")
	(title_block
		(title "01162023_DA0F0TEBIF0_F0T_Expander_BD_F_brd_V02_OCP.brd")
		(comment 1 "Grand Teton / footprints 7037-7042 of 9728")
	)
	(layers
		(0 "F.Cu" signal "TOP")
		(4 "In1.Cu" signal "GND")
		(6 "In2.Cu" signal "VCC")
		(8 "In3.Cu" signal "VCC1")
		(10 "In4.Cu" signal "GND1")
		(12 "In5.Cu" signal "IN1")
		(14 "In6.Cu" signal "GND2")
		(16 "In7.Cu" signal "IN2")
		(18 "In8.Cu" signal "GND3")
		(20 "In9.Cu" signal "IN3")
		(22 "In10.Cu" signal "GND4")
		(24 "In11.Cu" signal "IN4")
		(26 "In12.Cu" signal "GND5")
		(28 "In13.Cu" signal "IN5")
		(30 "In14.Cu" signal "GND6")
		(32 "In15.Cu" signal "IN6")
		(34 "In16.Cu" signal "GND7")
		(2 "B.Cu" signal "BOTTOM")
		(9 "F.Adhes" user "F.Adhesive")
		(11 "B.Adhes" user "B.Adhesive")
		(13 "F.Paste" user "Package Geometry/Pastemask Top")
		(15 "B.Paste" user "Package Geometry/Pastemask Bottom")
		(5 "F.SilkS" user "Ref Des/Silkscreen Top")
		(7 "B.SilkS" user "Ref Des/Silkscreen Bottom")
		(1 "F.Mask" user "Board Geometry/Soldermask Top")
		(3 "B.Mask" user "Board Geometry/Soldermask Bottom")
		(17 "Dwgs.User" user "User.Drawings")
		(19 "Cmts.User" user "User.Comments")
		(21 "Eco1.User" user "User.Eco1")
		(23 "Eco2.User" user "User.Eco2")
		(25 "Edge.Cuts" user "Board Geometry/Outline")
		(27 "Margin" user)
		(31 "F.CrtYd" user "Package Geometry/Place Bound Top")
		(29 "B.CrtYd" user "Package Geometry/Place Bound Bottom")
		(35 "F.Fab" user "Ref Des/Assembly Top")
		(33 "B.Fab" user "Ref Des/Assembly Bottom")
	)
	(footprint ""
		(layer "F.Cu")
		(at 195.562474 -22.937216 90)
		(property "Reference" "R1683"
			(at 0 0 90)
			(layer "F.SilkS")
			(hide yes)
			(effects
				(font
					(size 1.27 1.27)
				)
			)
		)
		(property "Value" ""
			(at 0 0 90)
			(layer "F.Fab")
			(effects
				(font
					(size 1.27 1.27)
				)
			)
		)
		(duplicate_pad_numbers_are_jumpers no)
		(fp_line
			(start 0.7874 -0.4064)
			(end 0.7874 0.4064)
			(stroke
				(width 0.1524)
				(type default)
			)
			(layer "F.SilkS")
		)
		(fp_line
			(start -0.7874 -0.4064)
			(end 0.7874 -0.4064)
			(stroke
				(width 0.1524)
				(type default)
			)
			(layer "F.SilkS")
		)
		(fp_line
			(start 0.7874 0.4064)
			(end -0.7874 0.4064)
			(stroke
				(width 0.1524)
				(type default)
			)
			(layer "F.SilkS")
		)
		(fp_line
			(start -0.7874 0.4064)
			(end -0.7874 -0.4064)
			(stroke
				(width 0.1524)
				(type default)
			)
			(layer "F.SilkS")
		)
		(fp_line
			(start -0.12065 -0.305054)
			(end -0.12065 -0.2794)
			(stroke
				(width 0.1)
				(type default)
			)
			(layer "F.Fab")
		)
		(fp_line
			(start -0.67945 -0.305054)
			(end -0.12065 -0.305054)
			(stroke
				(width 0.1)
				(type default)
			)
			(layer "F.Fab")
		)
		(fp_line
			(start 0.67945 -0.3048)
			(end 0.67945 0.3048)
			(stroke
				(width 0.1)
				(type default)
			)
			(layer "F.Fab")
		)
		(fp_line
			(start 0.12065 -0.3048)
			(end 0.67945 -0.3048)
			(stroke
				(width 0.1)
				(type default)
			)
			(layer "F.Fab")
		)
		(fp_line
			(start 0.12065 -0.2794)
			(end 0.12065 -0.3048)
			(stroke
				(width 0.1)
				(type default)
			)
			(layer "F.Fab")
		)
		(fp_line
			(start -0.12065 -0.2794)
			(end 0.12065 -0.2794)
			(stroke
				(width 0.1)
				(type default)
			)
			(layer "F.Fab")
		)
		(fp_line
			(start 0.120396 0.2794)
			(end -0.12065 0.2794)
			(stroke
				(width 0.1)
				(type default)
			)
			(layer "F.Fab")
		)
		(fp_line
			(start -0.12065 0.2794)
			(end -0.12065 0.3048)
			(stroke
				(width 0.1)
				(type default)
			)
			(layer "F.Fab")
		)
		(fp_line
			(start 0.67945 0.3048)
			(end 0.120396 0.3048)
			(stroke
				(width 0.1)
				(type default)
			)
			(layer "F.Fab")
		)
		(fp_line
			(start 0.120396 0.3048)
			(end 0.120396 0.2794)
			(stroke
				(width 0.1)
				(type default)
			)
			(layer "F.Fab")
		)
		(fp_line
			(start -0.12065 0.3048)
			(end -0.67945 0.3048)
			(stroke
				(width 0.1)
				(type default)
			)
			(layer "F.Fab")
		)
		(fp_line
			(start -0.67945 0.3048)
			(end -0.67945 -0.305054)
			(stroke
				(width 0.1)
				(type default)
			)
			(layer "F.Fab")
		)
		(pad "1" smd circle
			(at -0.40005 0 90)
			(size 0 0)
			(layers "F.Cu" "F.Mask" "F.Paste")
			(net "SMB_BIC_I2C9_MUX0_SSD6_R_SDA")
		)
		(pad "2" smd circle
			(at 0.40005 0 90)
			(size 0 0)
			(layers "F.Cu" "F.Mask" "F.Paste")
			(net "SMB_ISO_SSD6_SDA")
		)
	)
	(footprint ""
		(layer "F.Cu")
		(at 322.839334 -293.47287 -90)
		(property "Reference" "U315"
			(at -0.516382 -4.855972 90)
			(unlocked yes)
			(layer "F.SilkS")
			(effects
				(font
					(size 0.7874 0.5842)
					(thickness 0.1524)
				)
			)
		)
		(property "Value" ""
			(at 0 0 270)
			(layer "F.Fab")
			(effects
				(font
					(size 1.27 1.27)
				)
			)
		)
		(duplicate_pad_numbers_are_jumpers no)
		(fp_line
			(start -1.463548 1.549908)
			(end -1.463548 -1.549908)
			(stroke
				(width 0.1524)
				(type default)
			)
			(layer "F.SilkS")
		)
		(fp_line
			(start 1.463548 1.549908)
			(end -1.463548 1.549908)
			(stroke
				(width 0.1524)
				(type default)
			)
			(layer "F.SilkS")
		)
		(fp_line
			(start 0 -0.762)
			(end 0.762 -1.549908)
			(stroke
				(width 0.1524)
				(type default)
			)
			(layer "F.SilkS")
		)
		(fp_line
			(start -1.463548 -1.549908)
			(end -0.787908 -1.549908)
			(stroke
				(width 0.1524)
				(type default)
			)
			(layer "F.SilkS")
		)
		(fp_line
			(start -0.787908 -1.549908)
			(end 0 -0.762)
			(stroke
				(width 0.1524)
				(type default)
			)
			(layer "F.SilkS")
		)
		(fp_line
			(start 0.762 -1.549908)
			(end 1.463548 -1.549908)
			(stroke
				(width 0.1524)
				(type default)
			)
			(layer "F.SilkS")
		)
		(fp_line
			(start 1.463548 -1.549908)
			(end 1.463548 1.549908)
			(stroke
				(width 0.1524)
				(type default)
			)
			(layer "F.SilkS")
		)
		(fp_poly
			(pts
				(xy -3.4798 -1.359916) (xy -2.86004 -1.050036) (xy -3.4798 -0.740156)
			)
			(stroke
				(width 0)
				(type default)
			)
			(fill yes)
			(layer "F.SilkS")
		)
		(fp_line
			(start -1.549908 1.549908)
			(end -1.549908 -1.549908)
			(stroke
				(width 0.1)
				(type default)
			)
			(layer "F.Fab")
		)
		(fp_line
			(start 1.549908 1.549908)
			(end -1.549908 1.549908)
			(stroke
				(width 0.1)
				(type default)
			)
			(layer "F.Fab")
		)
		(fp_line
			(start -1.549908 -1.549908)
			(end 1.549908 -1.549908)
			(stroke
				(width 0.1)
				(type default)
			)
			(layer "F.Fab")
		)
		(fp_line
			(start 1.549908 -1.549908)
			(end 1.549908 1.549908)
			(stroke
				(width 0.1)
				(type default)
			)
			(layer "F.Fab")
		)
		(fp_poly
			(pts
				(xy -3.4798 -1.359916) (xy -2.86004 -1.050036) (xy -3.4798 -0.740156)
			)
			(stroke
				(width 0)
				(type default)
			)
			(fill yes)
			(layer "F.Fab")
		)
		(pad "1" smd rect
			(at -2.175002 -1.050036)
			(size 0.6096 1.1684)
			(layers "F.Cu" "F.Mask" "F.Paste")
			(net "P1V8_PEX")
		)
		(pad "2" smd rect
			(at -2.175002 -0.32512)
			(size 0.4318 1.1684)
			(layers "F.Cu" "F.Mask" "F.Paste")
			(net "I2C_PEX2_HOST_R_SCL")
		)
		(pad "3" smd rect
			(at -2.175002 0.32512)
			(size 0.4318 1.1684)
			(layers "F.Cu" "F.Mask" "F.Paste")
			(net "I2C_PEX2_HOST_R_SDA")
		)
		(pad "4" smd rect
			(at -2.175002 1.050036)
			(size 0.6096 1.1684)
			(layers "F.Cu" "F.Mask" "F.Paste")
			(net "GND")
		)
		(pad "5" smd rect
			(at 2.175002 1.050036)
			(size 0.6096 1.1684)
			(layers "F.Cu" "F.Mask" "F.Paste")
			(net "PWRGD_P1V8_PEX2_R")
		)
		(pad "6" smd rect
			(at 2.175002 0.32512)
			(size 0.4318 1.1684)
			(layers "F.Cu" "F.Mask" "F.Paste")
			(net "SMB_PEX2_HOST_LS_SDA")
		)
		(pad "7" smd rect
			(at 2.175002 -0.32512)
			(size 0.4318 1.1684)
			(layers "F.Cu" "F.Mask" "F.Paste")
			(net "SMB_PEX2_HOST_LS_SCL")
		)
		(pad "8" smd rect
			(at 2.175002 -1.050036)
			(size 0.6096 1.1684)
			(layers "F.Cu" "F.Mask" "F.Paste")
			(net "P3V3_AUX")
		)
	)
	(footprint ""
		(layer "F.Cu")
		(at 383.66954 -256.888234 -90)
		(property "Reference" "R4593"
			(at 0 0 270)
			(layer "F.SilkS")
			(hide yes)
			(effects
				(font
					(size 1.27 1.27)
				)
			)
		)
		(property "Value" ""
			(at 0 0 270)
			(layer "F.Fab")
			(effects
				(font
					(size 1.27 1.27)
				)
			)
		)
		(duplicate_pad_numbers_are_jumpers no)
		(fp_line
			(start -0.7874 0.4064)
			(end -0.7874 -0.4064)
			(stroke
				(width 0.1524)
				(type default)
			)
			(layer "F.SilkS")
		)
		(fp_line
			(start 0.7874 0.4064)
			(end -0.7874 0.4064)
			(stroke
				(width 0.1524)
				(type default)
			)
			(layer "F.SilkS")
		)
		(fp_line
			(start -0.7874 -0.4064)
			(end 0.7874 -0.4064)
			(stroke
				(width 0.1524)
				(type default)
			)
			(layer "F.SilkS")
		)
		(fp_line
			(start 0.7874 -0.4064)
			(end 0.7874 0.4064)
			(stroke
				(width 0.1524)
				(type default)
			)
			(layer "F.SilkS")
		)
		(fp_line
			(start -0.67945 0.3048)
			(end -0.67945 -0.305054)
			(stroke
				(width 0.1)
				(type default)
			)
			(layer "F.Fab")
		)
		(fp_line
			(start -0.12065 0.3048)
			(end -0.67945 0.3048)
			(stroke
				(width 0.1)
				(type default)
			)
			(layer "F.Fab")
		)
		(fp_line
			(start 0.120396 0.3048)
			(end 0.120396 0.2794)
			(stroke
				(width 0.1)
				(type default)
			)
			(layer "F.Fab")
		)
		(fp_line
			(start 0.67945 0.3048)
			(end 0.120396 0.3048)
			(stroke
				(width 0.1)
				(type default)
			)
			(layer "F.Fab")
		)
		(fp_line
			(start -0.12065 0.2794)
			(end -0.12065 0.3048)
			(stroke
				(width 0.1)
				(type default)
			)
			(layer "F.Fab")
		)
		(fp_line
			(start 0.120396 0.2794)
			(end -0.12065 0.2794)
			(stroke
				(width 0.1)
				(type default)
			)
			(layer "F.Fab")
		)
		(fp_line
			(start -0.12065 -0.2794)
			(end 0.12065 -0.2794)
			(stroke
				(width 0.1)
				(type default)
			)
			(layer "F.Fab")
		)
		(fp_line
			(start 0.12065 -0.2794)
			(end 0.12065 -0.3048)
			(stroke
				(width 0.1)
				(type default)
			)
			(layer "F.Fab")
		)
		(fp_line
			(start 0.12065 -0.3048)
			(end 0.67945 -0.3048)
			(stroke
				(width 0.1)
				(type default)
			)
			(layer "F.Fab")
		)
		(fp_line
			(start 0.67945 -0.3048)
			(end 0.67945 0.3048)
			(stroke
				(width 0.1)
				(type default)
			)
			(layer "F.Fab")
		)
		(fp_line
			(start -0.67945 -0.305054)
			(end -0.12065 -0.305054)
			(stroke
				(width 0.1)
				(type default)
			)
			(layer "F.Fab")
		)
		(fp_line
			(start -0.12065 -0.305054)
			(end -0.12065 -0.2794)
			(stroke
				(width 0.1)
				(type default)
			)
			(layer "F.Fab")
		)
		(pad "1" smd circle
			(at -0.40005 0 270)
			(size 0 0)
			(layers "F.Cu" "F.Mask" "F.Paste")
			(net "PCEPLL5_VDDA18_PEX3")
		)
		(pad "2" smd circle
			(at 0.40005 0 270)
			(size 0 0)
			(layers "F.Cu" "F.Mask" "F.Paste")
			(net "PCEPLL5_VDDA18_PEX3_R")
		)
	)
	(footprint ""
		(layer "F.Cu")
		(at 87.819992 -289.230816 -90)
		(property "Reference" "R3878"
			(at 0 0 270)
			(layer "F.SilkS")
			(hide yes)
			(effects
				(font
					(size 1.27 1.27)
				)
			)
		)
		(property "Value" ""
			(at 0 0 270)
			(layer "F.Fab")
			(effects
				(font
					(size 1.27 1.27)
				)
			)
		)
		(duplicate_pad_numbers_are_jumpers no)
		(fp_line
			(start -0.7874 0.4064)
			(end -0.7874 -0.4064)
			(stroke
				(width 0.1524)
				(type default)
			)
			(layer "F.SilkS")
		)
		(fp_line
			(start 0.7874 0.4064)
			(end -0.7874 0.4064)
			(stroke
				(width 0.1524)
				(type default)
			)
			(layer "F.SilkS")
		)
		(fp_line
			(start -0.7874 -0.4064)
			(end 0.7874 -0.4064)
			(stroke
				(width 0.1524)
				(type default)
			)
			(layer "F.SilkS")
		)
		(fp_line
			(start 0.7874 -0.4064)
			(end 0.7874 0.4064)
			(stroke
				(width 0.1524)
				(type default)
			)
			(layer "F.SilkS")
		)
		(fp_line
			(start -0.67945 0.3048)
			(end -0.67945 -0.305054)
			(stroke
				(width 0.1)
				(type default)
			)
			(layer "F.Fab")
		)
		(fp_line
			(start -0.12065 0.3048)
			(end -0.67945 0.3048)
			(stroke
				(width 0.1)
				(type default)
			)
			(layer "F.Fab")
		)
		(fp_line
			(start 0.120396 0.3048)
			(end 0.120396 0.2794)
			(stroke
				(width 0.1)
				(type default)
			)
			(layer "F.Fab")
		)
		(fp_line
			(start 0.67945 0.3048)
			(end 0.120396 0.3048)
			(stroke
				(width 0.1)
				(type default)
			)
			(layer "F.Fab")
		)
		(fp_line
			(start -0.12065 0.2794)
			(end -0.12065 0.3048)
			(stroke
				(width 0.1)
				(type default)
			)
			(layer "F.Fab")
		)
		(fp_line
			(start 0.120396 0.2794)
			(end -0.12065 0.2794)
			(stroke
				(width 0.1)
				(type default)
			)
			(layer "F.Fab")
		)
		(fp_line
			(start -0.12065 -0.2794)
			(end 0.12065 -0.2794)
			(stroke
				(width 0.1)
				(type default)
			)
			(layer "F.Fab")
		)
		(fp_line
			(start 0.12065 -0.2794)
			(end 0.12065 -0.3048)
			(stroke
				(width 0.1)
				(type default)
			)
			(layer "F.Fab")
		)
		(fp_line
			(start 0.12065 -0.3048)
			(end 0.67945 -0.3048)
			(stroke
				(width 0.1)
				(type default)
			)
			(layer "F.Fab")
		)
		(fp_line
			(start 0.67945 -0.3048)
			(end 0.67945 0.3048)
			(stroke
				(width 0.1)
				(type default)
			)
			(layer "F.Fab")
		)
		(fp_line
			(start -0.67945 -0.305054)
			(end -0.12065 -0.305054)
			(stroke
				(width 0.1)
				(type default)
			)
			(layer "F.Fab")
		)
		(fp_line
			(start -0.12065 -0.305054)
			(end -0.12065 -0.2794)
			(stroke
				(width 0.1)
				(type default)
			)
			(layer "F.Fab")
		)
		(pad "1" smd circle
			(at -0.40005 0 270)
			(size 0 0)
			(layers "F.Cu" "F.Mask" "F.Paste")
			(net "SMB_PEX0_HOST_LS_SDA")
		)
		(pad "2" smd circle
			(at 0.40005 0 270)
			(size 0 0)
			(layers "F.Cu" "F.Mask" "F.Paste")
			(net "P3V3_AUX")
		)
	)
	(footprint ""
		(layer "F.Cu")
		(at 225.026474 -136.669272 -90)
		(property "Reference" "R4218"
			(at 0 0 270)
			(layer "F.SilkS")
			(hide yes)
			(effects
				(font
					(size 1.27 1.27)
				)
			)
		)
		(property "Value" ""
			(at 0 0 270)
			(layer "F.Fab")
			(effects
				(font
					(size 1.27 1.27)
				)
			)
		)
		(duplicate_pad_numbers_are_jumpers no)
		(fp_line
			(start -0.7874 0.4064)
			(end -0.7874 -0.4064)
			(stroke
				(width 0.1524)
				(type default)
			)
			(layer "F.SilkS")
		)
		(fp_line
			(start 0.7874 0.4064)
			(end -0.7874 0.4064)
			(stroke
				(width 0.1524)
				(type default)
			)
			(layer "F.SilkS")
		)
		(fp_line
			(start -0.7874 -0.4064)
			(end 0.7874 -0.4064)
			(stroke
				(width 0.1524)
				(type default)
			)
			(layer "F.SilkS")
		)
		(fp_line
			(start 0.7874 -0.4064)
			(end 0.7874 0.4064)
			(stroke
				(width 0.1524)
				(type default)
			)
			(layer "F.SilkS")
		)
		(fp_line
			(start -0.67945 0.3048)
			(end -0.67945 -0.305054)
			(stroke
				(width 0.1)
				(type default)
			)
			(layer "F.Fab")
		)
		(fp_line
			(start -0.12065 0.3048)
			(end -0.67945 0.3048)
			(stroke
				(width 0.1)
				(type default)
			)
			(layer "F.Fab")
		)
		(fp_line
			(start 0.120396 0.3048)
			(end 0.120396 0.2794)
			(stroke
				(width 0.1)
				(type default)
			)
			(layer "F.Fab")
		)
		(fp_line
			(start 0.67945 0.3048)
			(end 0.120396 0.3048)
			(stroke
				(width 0.1)
				(type default)
			)
			(layer "F.Fab")
		)
		(fp_line
			(start -0.12065 0.2794)
			(end -0.12065 0.3048)
			(stroke
				(width 0.1)
				(type default)
			)
			(layer "F.Fab")
		)
		(fp_line
			(start 0.120396 0.2794)
			(end -0.12065 0.2794)
			(stroke
				(width 0.1)
				(type default)
			)
			(layer "F.Fab")
		)
		(fp_line
			(start -0.12065 -0.2794)
			(end 0.12065 -0.2794)
			(stroke
				(width 0.1)
				(type default)
			)
			(layer "F.Fab")
		)
		(fp_line
			(start 0.12065 -0.2794)
			(end 0.12065 -0.3048)
			(stroke
				(width 0.1)
				(type default)
			)
			(layer "F.Fab")
		)
		(fp_line
			(start 0.12065 -0.3048)
			(end 0.67945 -0.3048)
			(stroke
				(width 0.1)
				(type default)
			)
			(layer "F.Fab")
		)
		(fp_line
			(start 0.67945 -0.3048)
			(end 0.67945 0.3048)
			(stroke
				(width 0.1)
				(type default)
			)
			(layer "F.Fab")
		)
		(fp_line
			(start -0.67945 -0.305054)
			(end -0.12065 -0.305054)
			(stroke
				(width 0.1)
				(type default)
			)
			(layer "F.Fab")
		)
		(fp_line
			(start -0.12065 -0.305054)
			(end -0.12065 -0.2794)
			(stroke
				(width 0.1)
				(type default)
			)
			(layer "F.Fab")
		)
		(pad "1" smd circle
			(at -0.40005 0 270)
			(size 0 0)
			(layers "F.Cu" "F.Mask" "F.Paste")
			(net "SMB_CK440_PEX_CLK_SDA")
		)
		(pad "2" smd circle
			(at 0.40005 0 270)
			(size 0 0)
			(layers "F.Cu" "F.Mask" "F.Paste")
			(net "SMB_CLK_ISO_R_SDA")
		)
	)
	(footprint ""
		(layer "F.Cu")
		(at 334.240124 -350.098614 90)
		(property "Reference" "C571"
			(at 0 0 90)
			(layer "F.SilkS")
			(hide yes)
			(effects
				(font
					(size 1.27 1.27)
				)
			)
		)
		(property "Value" ""
			(at 0 0 90)
			(layer "F.Fab")
			(effects
				(font
					(size 1.27 1.27)
				)
			)
		)
		(duplicate_pad_numbers_are_jumpers no)
		(fp_line
			(start 0.299974 -0.150114)
			(end 0.299974 0.150114)
			(stroke
				(width 0.1)
				(type default)
			)
			(layer "F.Fab")
		)
		(fp_line
			(start -0.299974 -0.150114)
			(end 0.299974 -0.150114)
			(stroke
				(width 0.1)
				(type default)
			)
			(layer "F.Fab")
		)
		(fp_line
			(start 0.299974 0.150114)
			(end -0.299974 0.150114)
			(stroke
				(width 0.1)
				(type default)
			)
			(layer "F.Fab")
		)
		(fp_line
			(start -0.299974 0.150114)
			(end -0.299974 -0.150114)
			(stroke
				(width 0.1)
				(type default)
			)
			(layer "F.Fab")
		)
		(pad "1" smd rect
			(at -0.2667 0 90)
			(size 0.3048 0.381)
			(layers "F.Cu" "F.Mask" "F.Paste")
			(net "P5E_PEX2_STN6_TX_DP<101>")
		)
		(pad "2" smd rect
			(at 0.2667 0 90)
			(size 0.3048 0.381)
			(layers "F.Cu" "F.Mask" "F.Paste")
			(net "P5E_PEX2_STN6_TX_C_DP<101>")
		)
	)
)
